(kicad_pcb
	(version 20260206)
	(generator "pcbnew")
	(generator_version "10.0")
	(general
		(thickness 1.6)
		(legacy_teardrops no)
	)
	(paper "A4")
	(title_block
		(title "01162023_DA0F0TEBIF0_F0T_Expander_BD_F_brd_V02_OCP.brd")
		(comment 1 "Grand Teton / footprints 1003-1008 of 9728")
	)
	(layers
		(0 "F.Cu" signal "TOP")
		(4 "In1.Cu" signal "GND")
		(6 "In2.Cu" signal "VCC")
		(8 "In3.Cu" signal "VCC1")
		(10 "In4.Cu" signal "GND1")
		(12 "In5.Cu" signal "IN1")
		(14 "In6.Cu" signal "GND2")
		(16 "In7.Cu" signal "IN2")
		(18 "In8.Cu" signal "GND3")
		(20 "In9.Cu" signal "IN3")
		(22 "In10.Cu" signal "GND4")
		(24 "In11.Cu" signal "IN4")
		(26 "In12.Cu" signal "GND5")
		(28 "In13.Cu" signal "IN5")
		(30 "In14.Cu" signal "GND6")
		(32 "In15.Cu" signal "IN6")
		(34 "In16.Cu" signal "GND7")
		(2 "B.Cu" signal "BOTTOM")
		(9 "F.Adhes" user "F.Adhesive")
		(11 "B.Adhes" user "B.Adhesive")
		(13 "F.Paste" user "Package Geometry/Pastemask Top")
		(15 "B.Paste" user "Package Geometry/Pastemask Bottom")
		(5 "F.SilkS" user "Ref Des/Silkscreen Top")
		(7 "B.SilkS" user "Ref Des/Silkscreen Bottom")
		(1 "F.Mask" user "Board Geometry/Soldermask Top")
		(3 "B.Mask" user "Board Geometry/Soldermask Bottom")
		(17 "Dwgs.User" user "User.Drawings")
		(19 "Cmts.User" user "User.Comments")
		(21 "Eco1.User" user "User.Eco1")
		(23 "Eco2.User" user "User.Eco2")
		(25 "Edge.Cuts" user "Board Geometry/Outline")
		(27 "Margin" user)
		(31 "F.CrtYd" user "Package Geometry/Place Bound Top")
		(29 "B.CrtYd" user "Package Geometry/Place Bound Bottom")
		(35 "F.Fab" user "Ref Des/Assembly Top")
		(33 "B.Fab" user "Ref Des/Assembly Bottom")
	)
	(footprint ""
		(layer "F.Cu")
		(at 427.42612 -37.929566 90)
		(property "Reference" "R5585"
			(at 0 0 90)
			(layer "F.SilkS")
			(hide yes)
			(effects
				(font
					(size 1.27 1.27)
				)
			)
		)
		(property "Value" ""
			(at 0 0 90)
			(layer "F.Fab")
			(effects
				(font
					(size 1.27 1.27)
				)
			)
		)
		(duplicate_pad_numbers_are_jumpers no)
		(fp_line
			(start 0.7874 -0.4064)
			(end 0.7874 0.4064)
			(stroke
				(width 0.1524)
				(type default)
			)
			(layer "F.SilkS")
		)
		(fp_line
			(start -0.7874 -0.4064)
			(end 0.7874 -0.4064)
			(stroke
				(width 0.1524)
				(type default)
			)
			(layer "F.SilkS")
		)
		(fp_line
			(start 0.7874 0.4064)
			(end -0.7874 0.4064)
			(stroke
				(width 0.1524)
				(type default)
			)
			(layer "F.SilkS")
		)
		(fp_line
			(start -0.7874 0.4064)
			(end -0.7874 -0.4064)
			(stroke
				(width 0.1524)
				(type default)
			)
			(layer "F.SilkS")
		)
		(fp_line
			(start -0.12065 -0.305054)
			(end -0.12065 -0.2794)
			(stroke
				(width 0.1)
				(type default)
			)
			(layer "F.Fab")
		)
		(fp_line
			(start -0.67945 -0.305054)
			(end -0.12065 -0.305054)
			(stroke
				(width 0.1)
				(type default)
			)
			(layer "F.Fab")
		)
		(fp_line
			(start 0.67945 -0.3048)
			(end 0.67945 0.3048)
			(stroke
				(width 0.1)
				(type default)
			)
			(layer "F.Fab")
		)
		(fp_line
			(start 0.12065 -0.3048)
			(end 0.67945 -0.3048)
			(stroke
				(width 0.1)
				(type default)
			)
			(layer "F.Fab")
		)
		(fp_line
			(start 0.12065 -0.2794)
			(end 0.12065 -0.3048)
			(stroke
				(width 0.1)
				(type default)
			)
			(layer "F.Fab")
		)
		(fp_line
			(start -0.12065 -0.2794)
			(end 0.12065 -0.2794)
			(stroke
				(width 0.1)
				(type default)
			)
			(layer "F.Fab")
		)
		(fp_line
			(start 0.120396 0.2794)
			(end -0.12065 0.2794)
			(stroke
				(width 0.1)
				(type default)
			)
			(layer "F.Fab")
		)
		(fp_line
			(start -0.12065 0.2794)
			(end -0.12065 0.3048)
			(stroke
				(width 0.1)
				(type default)
			)
			(layer "F.Fab")
		)
		(fp_line
			(start 0.67945 0.3048)
			(end 0.120396 0.3048)
			(stroke
				(width 0.1)
				(type default)
			)
			(layer "F.Fab")
		)
		(fp_line
			(start 0.120396 0.3048)
			(end 0.120396 0.2794)
			(stroke
				(width 0.1)
				(type default)
			)
			(layer "F.Fab")
		)
		(fp_line
			(start -0.12065 0.3048)
			(end -0.67945 0.3048)
			(stroke
				(width 0.1)
				(type default)
			)
			(layer "F.Fab")
		)
		(fp_line
			(start -0.67945 0.3048)
			(end -0.67945 -0.305054)
			(stroke
				(width 0.1)
				(type default)
			)
			(layer "F.Fab")
		)
		(pad "1" smd circle
			(at -0.40005 0 90)
			(size 0 0)
			(layers "F.Cu" "F.Mask" "F.Paste")
			(net "SSD15_AUX_P3V3_EN_R")
		)
		(pad "2" smd circle
			(at 0.40005 0 90)
			(size 0 0)
			(layers "F.Cu" "F.Mask" "F.Paste")
			(net "SSD15_AUX_P3V3_EN")
		)
	)
	(footprint ""
		(layer "F.Cu")
		(at 76.273914 -26.31186 -90)
		(property "Reference" "U400"
			(at -0.00254 -2.264156 90)
			(unlocked yes)
			(layer "F.SilkS")
			(effects
				(font
					(size 0.7874 0.5842)
					(thickness 0.1524)
				)
			)
		)
		(property "Value" ""
			(at 0 0 270)
			(layer "F.Fab")
			(effects
				(font
					(size 1.27 1.27)
				)
			)
		)
		(duplicate_pad_numbers_are_jumpers no)
		(fp_line
			(start -1.949958 1.610106)
			(end -1.949958 -1.610106)
			(stroke
				(width 0.1524)
				(type default)
			)
			(layer "F.SilkS")
		)
		(fp_line
			(start 1.949958 1.610106)
			(end -1.949958 1.610106)
			(stroke
				(width 0.1524)
				(type default)
			)
			(layer "F.SilkS")
		)
		(fp_line
			(start 1.949958 -1.560068)
			(end 1.949958 1.610106)
			(stroke
				(width 0.1524)
				(type default)
			)
			(layer "F.SilkS")
		)
		(fp_line
			(start -1.949958 -1.610106)
			(end 1.949958 -1.610106)
			(stroke
				(width 0.1524)
				(type default)
			)
			(layer "F.SilkS")
		)
		(fp_line
			(start -0.750062 1.560068)
			(end -0.750062 -1.560068)
			(stroke
				(width 0.1)
				(type default)
			)
			(layer "F.Fab")
		)
		(fp_line
			(start 0.750062 1.560068)
			(end -0.750062 1.560068)
			(stroke
				(width 0.1)
				(type default)
			)
			(layer "F.Fab")
		)
		(fp_line
			(start -0.750062 -1.560068)
			(end 0.750062 -1.560068)
			(stroke
				(width 0.1)
				(type default)
			)
			(layer "F.Fab")
		)
		(fp_line
			(start 0.750062 -1.560068)
			(end 0.750062 1.560068)
			(stroke
				(width 0.1)
				(type default)
			)
			(layer "F.Fab")
		)
		(pad "D" smd rect
			(at 1.100074 0 180)
			(size 1.016 1.4224)
			(layers "F.Cu" "F.Mask" "F.Paste")
			(net "SSD2_LED_ISO_N")
		)
		(pad "G" smd rect
			(at -1.100074 -0.94996 180)
			(size 1.016 1.4224)
			(layers "F.Cu" "F.Mask" "F.Paste")
			(net "SSD2_LED_R")
		)
		(pad "S" smd rect
			(at -1.100074 0.94996 180)
			(size 1.016 1.4224)
			(layers "F.Cu" "F.Mask" "F.Paste")
			(net "GND")
		)
	)
	(footprint ""
		(layer "F.Cu")
		(at 207.376268 -297.46448 180)
		(property "Reference" "R3942"
			(at 0 0 180)
			(layer "F.SilkS")
			(hide yes)
			(effects
				(font
					(size 1.27 1.27)
				)
			)
		)
		(property "Value" ""
			(at 0 0 180)
			(layer "F.Fab")
			(effects
				(font
					(size 1.27 1.27)
				)
			)
		)
		(duplicate_pad_numbers_are_jumpers no)
		(fp_line
			(start 0.7874 0.4064)
			(end -0.7874 0.4064)
			(stroke
				(width 0.1524)
				(type default)
			)
			(layer "F.SilkS")
		)
		(fp_line
			(start 0.7874 -0.4064)
			(end 0.7874 0.4064)
			(stroke
				(width 0.1524)
				(type default)
			)
			(layer "F.SilkS")
		)
		(fp_line
			(start -0.7874 0.4064)
			(end -0.7874 -0.4064)
			(stroke
				(width 0.1524)
				(type default)
			)
			(layer "F.SilkS")
		)
		(fp_line
			(start -0.7874 -0.4064)
			(end 0.7874 -0.4064)
			(stroke
				(width 0.1524)
				(type default)
			)
			(layer "F.SilkS")
		)
		(fp_line
			(start 0.67945 0.3048)
			(end 0.120396 0.3048)
			(stroke
				(width 0.1)
				(type default)
			)
			(layer "F.Fab")
		)
		(fp_line
			(start 0.67945 -0.3048)
			(end 0.67945 0.3048)
			(stroke
				(width 0.1)
				(type default)
			)
			(layer "F.Fab")
		)
		(fp_line
			(start 0.12065 -0.2794)
			(end 0.12065 -0.3048)
			(stroke
				(width 0.1)
				(type default)
			)
			(layer "F.Fab")
		)
		(fp_line
			(start 0.12065 -0.3048)
			(end 0.67945 -0.3048)
			(stroke
				(width 0.1)
				(type default)
			)
			(layer "F.Fab")
		)
		(fp_line
			(start 0.120396 0.3048)
			(end 0.120396 0.2794)
			(stroke
				(width 0.1)
				(type default)
			)
			(layer "F.Fab")
		)
		(fp_line
			(start 0.120396 0.2794)
			(end -0.12065 0.2794)
			(stroke
				(width 0.1)
				(type default)
			)
			(layer "F.Fab")
		)
		(fp_line
			(start -0.12065 0.3048)
			(end -0.67945 0.3048)
			(stroke
				(width 0.1)
				(type default)
			)
			(layer "F.Fab")
		)
		(fp_line
			(start -0.12065 0.2794)
			(end -0.12065 0.3048)
			(stroke
				(width 0.1)
				(type default)
			)
			(layer "F.Fab")
		)
		(fp_line
			(start -0.12065 -0.2794)
			(end 0.12065 -0.2794)
			(stroke
				(width 0.1)
				(type default)
			)
			(layer "F.Fab")
		)
		(fp_line
			(start -0.12065 -0.305054)
			(end -0.12065 -0.2794)
			(stroke
				(width 0.1)
				(type default)
			)
			(layer "F.Fab")
		)
		(fp_line
			(start -0.67945 0.3048)
			(end -0.67945 -0.305054)
			(stroke
				(width 0.1)
				(type default)
			)
			(layer "F.Fab")
		)
		(fp_line
			(start -0.67945 -0.305054)
			(end -0.12065 -0.305054)
			(stroke
				(width 0.1)
				(type default)
			)
			(layer "F.Fab")
		)
		(pad "1" smd circle
			(at -0.40005 0 180)
			(size 0 0)
			(layers "F.Cu" "F.Mask" "F.Paste")
			(net "SMB_PEX1_HOST_LS_SCL")
		)
		(pad "2" smd circle
			(at 0.40005 0 180)
			(size 0 0)
			(layers "F.Cu" "F.Mask" "F.Paste")
			(net "I2C_PEX1_HOST_R_SCL")
		)
	)
	(footprint ""
		(layer "F.Cu")
		(at 248.819924 -88.039448 180)
		(property "Reference" "R1466"
			(at 0 0 180)
			(layer "F.SilkS")
			(hide yes)
			(effects
				(font
					(size 1.27 1.27)
				)
			)
		)
		(property "Value" ""
			(at 0 0 180)
			(layer "F.Fab")
			(effects
				(font
					(size 1.27 1.27)
				)
			)
		)
		(duplicate_pad_numbers_are_jumpers no)
		(fp_line
			(start 0.7874 0.4064)
			(end -0.7874 0.4064)
			(stroke
				(width 0.1524)
				(type default)
			)
			(layer "F.SilkS")
		)
		(fp_line
			(start 0.7874 -0.4064)
			(end 0.7874 0.4064)
			(stroke
				(width 0.1524)
				(type default)
			)
			(layer "F.SilkS")
		)
		(fp_line
			(start -0.7874 0.4064)
			(end -0.7874 -0.4064)
			(stroke
				(width 0.1524)
				(type default)
			)
			(layer "F.SilkS")
		)
		(fp_line
			(start -0.7874 -0.4064)
			(end 0.7874 -0.4064)
			(stroke
				(width 0.1524)
				(type default)
			)
			(layer "F.SilkS")
		)
		(fp_line
			(start 0.67945 0.3048)
			(end 0.120396 0.3048)
			(stroke
				(width 0.1)
				(type default)
			)
			(layer "F.Fab")
		)
		(fp_line
			(start 0.67945 -0.3048)
			(end 0.67945 0.3048)
			(stroke
				(width 0.1)
				(type default)
			)
			(layer "F.Fab")
		)
		(fp_line
			(start 0.12065 -0.2794)
			(end 0.12065 -0.3048)
			(stroke
				(width 0.1)
				(type default)
			)
			(layer "F.Fab")
		)
		(fp_line
			(start 0.12065 -0.3048)
			(end 0.67945 -0.3048)
			(stroke
				(width 0.1)
				(type default)
			)
			(layer "F.Fab")
		)
		(fp_line
			(start 0.120396 0.3048)
			(end 0.120396 0.2794)
			(stroke
				(width 0.1)
				(type default)
			)
			(layer "F.Fab")
		)
		(fp_line
			(start 0.120396 0.2794)
			(end -0.12065 0.2794)
			(stroke
				(width 0.1)
				(type default)
			)
			(layer "F.Fab")
		)
		(fp_line
			(start -0.12065 0.3048)
			(end -0.67945 0.3048)
			(stroke
				(width 0.1)
				(type default)
			)
			(layer "F.Fab")
		)
		(fp_line
			(start -0.12065 0.2794)
			(end -0.12065 0.3048)
			(stroke
				(width 0.1)
				(type default)
			)
			(layer "F.Fab")
		)
		(fp_line
			(start -0.12065 -0.2794)
			(end 0.12065 -0.2794)
			(stroke
				(width 0.1)
				(type default)
			)
			(layer "F.Fab")
		)
		(fp_line
			(start -0.12065 -0.305054)
			(end -0.12065 -0.2794)
			(stroke
				(width 0.1)
				(type default)
			)
			(layer "F.Fab")
		)
		(fp_line
			(start -0.67945 0.3048)
			(end -0.67945 -0.305054)
			(stroke
				(width 0.1)
				(type default)
			)
			(layer "F.Fab")
		)
		(fp_line
			(start -0.67945 -0.305054)
			(end -0.12065 -0.305054)
			(stroke
				(width 0.1)
				(type default)
			)
			(layer "F.Fab")
		)
		(pad "1" smd circle
			(at -0.40005 0 180)
			(size 0 0)
			(layers "F.Cu" "F.Mask" "F.Paste")
			(net "SMB_CK440_CLK_SDA")
		)
		(pad "2" smd circle
			(at 0.40005 0 180)
			(size 0 0)
			(layers "F.Cu" "F.Mask" "F.Paste")
			(net "SMB_CLK_ISO_R_SDA")
		)
	)
	(footprint ""
		(layer "F.Cu")
		(at 328.295 -233.553)
		(property "Reference" "R4385"
			(at 0 0 0)
			(layer "F.SilkS")
			(hide yes)
			(effects
				(font
					(size 1.27 1.27)
				)
			)
		)
		(property "Value" ""
			(at 0 0 0)
			(layer "F.Fab")
			(effects
				(font
					(size 1.27 1.27)
				)
			)
		)
		(duplicate_pad_numbers_are_jumpers no)
		(fp_line
			(start -0.7874 -0.4064)
			(end 0.7874 -0.4064)
			(stroke
				(width 0.1524)
				(type default)
			)
			(layer "F.SilkS")
		)
		(fp_line
			(start -0.7874 0.4064)
			(end -0.7874 -0.4064)
			(stroke
				(width 0.1524)
				(type default)
			)
			(layer "F.SilkS")
		)
		(fp_line
			(start 0.7874 -0.4064)
			(end 0.7874 0.4064)
			(stroke
				(width 0.1524)
				(type default)
			)
			(layer "F.SilkS")
		)
		(fp_line
			(start 0.7874 0.4064)
			(end -0.7874 0.4064)
			(stroke
				(width 0.1524)
				(type default)
			)
			(layer "F.SilkS")
		)
		(fp_line
			(start -0.67945 -0.305054)
			(end -0.12065 -0.305054)
			(stroke
				(width 0.1)
				(type default)
			)
			(layer "F.Fab")
		)
		(fp_line
			(start -0.67945 0.3048)
			(end -0.67945 -0.305054)
			(stroke
				(width 0.1)
				(type default)
			)
			(layer "F.Fab")
		)
		(fp_line
			(start -0.12065 -0.305054)
			(end -0.12065 -0.2794)
			(stroke
				(width 0.1)
				(type default)
			)
			(layer "F.Fab")
		)
		(fp_line
			(start -0.12065 -0.2794)
			(end 0.12065 -0.2794)
			(stroke
				(width 0.1)
				(type default)
			)
			(layer "F.Fab")
		)
		(fp_line
			(start -0.12065 0.2794)
			(end -0.12065 0.3048)
			(stroke
				(width 0.1)
				(type default)
			)
			(layer "F.Fab")
		)
		(fp_line
			(start -0.12065 0.3048)
			(end -0.67945 0.3048)
			(stroke
				(width 0.1)
				(type default)
			)
			(layer "F.Fab")
		)
		(fp_line
			(start 0.120396 0.2794)
			(end -0.12065 0.2794)
			(stroke
				(width 0.1)
				(type default)
			)
			(layer "F.Fab")
		)
		(fp_line
			(start 0.120396 0.3048)
			(end 0.120396 0.2794)
			(stroke
				(width 0.1)
				(type default)
			)
			(layer "F.Fab")
		)
		(fp_line
			(start 0.12065 -0.3048)
			(end 0.67945 -0.3048)
			(stroke
				(width 0.1)
				(type default)
			)
			(layer "F.Fab")
		)
		(fp_line
			(start 0.12065 -0.2794)
			(end 0.12065 -0.3048)
			(stroke
				(width 0.1)
				(type default)
			)
			(layer "F.Fab")
		)
		(fp_line
			(start 0.67945 -0.3048)
			(end 0.67945 0.3048)
			(stroke
				(width 0.1)
				(type default)
			)
			(layer "F.Fab")
		)
		(fp_line
			(start 0.67945 0.3048)
			(end 0.120396 0.3048)
			(stroke
				(width 0.1)
				(type default)
			)
			(layer "F.Fab")
		)
		(pad "1" smd circle
			(at -0.40005 0)
			(size 0 0)
			(layers "F.Cu" "F.Mask" "F.Paste")
			(net "RST_PEX_SYS_BUF_N")
		)
		(pad "2" smd circle
			(at 0.40005 0)
			(size 0 0)
			(layers "F.Cu" "F.Mask" "F.Paste")
			(net "P1V8_PEX")
		)
	)
	(footprint ""
		(layer "F.Cu")
		(at 205.102206 -306.074572 90)
		(property "Reference" "R1303"
			(at 0 0 90)
			(layer "F.SilkS")
			(hide yes)
			(effects
				(font
					(size 1.27 1.27)
				)
			)
		)
		(property "Value" ""
			(at 0 0 90)
			(layer "F.Fab")
			(effects
				(font
					(size 1.27 1.27)
				)
			)
		)
		(duplicate_pad_numbers_are_jumpers no)
		(fp_line
			(start 0.7874 -0.4064)
			(end 0.7874 0.4064)
			(stroke
				(width 0.1524)
				(type default)
			)
			(layer "F.SilkS")
		)
		(fp_line
			(start -0.7874 -0.4064)
			(end 0.7874 -0.4064)
			(stroke
				(width 0.1524)
				(type default)
			)
			(layer "F.SilkS")
		)
		(fp_line
			(start 0.7874 0.4064)
			(end -0.7874 0.4064)
			(stroke
				(width 0.1524)
				(type default)
			)
			(layer "F.SilkS")
		)
		(fp_line
			(start -0.7874 0.4064)
			(end -0.7874 -0.4064)
			(stroke
				(width 0.1524)
				(type default)
			)
			(layer "F.SilkS")
		)
		(fp_line
			(start -0.12065 -0.305054)
			(end -0.12065 -0.2794)
			(stroke
				(width 0.1)
				(type default)
			)
			(layer "F.Fab")
		)
		(fp_line
			(start -0.67945 -0.305054)
			(end -0.12065 -0.305054)
			(stroke
				(width 0.1)
				(type default)
			)
			(layer "F.Fab")
		)
		(fp_line
			(start 0.67945 -0.3048)
			(end 0.67945 0.3048)
			(stroke
				(width 0.1)
				(type default)
			)
			(layer "F.Fab")
		)
		(fp_line
			(start 0.12065 -0.3048)
			(end 0.67945 -0.3048)
			(stroke
				(width 0.1)
				(type default)
			)
			(layer "F.Fab")
		)
		(fp_line
			(start 0.12065 -0.2794)
			(end 0.12065 -0.3048)
			(stroke
				(width 0.1)
				(type default)
			)
			(layer "F.Fab")
		)
		(fp_line
			(start -0.12065 -0.2794)
			(end 0.12065 -0.2794)
			(stroke
				(width 0.1)
				(type default)
			)
			(layer "F.Fab")
		)
		(fp_line
			(start 0.120396 0.2794)
			(end -0.12065 0.2794)
			(stroke
				(width 0.1)
				(type default)
			)
			(layer "F.Fab")
		)
		(fp_line
			(start -0.12065 0.2794)
			(end -0.12065 0.3048)
			(stroke
				(width 0.1)
				(type default)
			)
			(layer "F.Fab")
		)
		(fp_line
			(start 0.67945 0.3048)
			(end 0.120396 0.3048)
			(stroke
				(width 0.1)
				(type default)
			)
			(layer "F.Fab")
		)
		(fp_line
			(start 0.120396 0.3048)
			(end 0.120396 0.2794)
			(stroke
				(width 0.1)
				(type default)
			)
			(layer "F.Fab")
		)
		(fp_line
			(start -0.12065 0.3048)
			(end -0.67945 0.3048)
			(stroke
				(width 0.1)
				(type default)
			)
			(layer "F.Fab")
		)
		(fp_line
			(start -0.67945 0.3048)
			(end -0.67945 -0.305054)
			(stroke
				(width 0.1)
				(type default)
			)
			(layer "F.Fab")
		)
		(pad "1" smd circle
			(at -0.40005 0 90)
			(size 0 0)
			(layers "F.Cu" "F.Mask" "F.Paste")
			(net "PEX1_SPARE4")
		)
		(pad "2" smd circle
			(at 0.40005 0 90)
			(size 0 0)
			(layers "F.Cu" "F.Mask" "F.Paste")
			(net "P1V8_PEX")
		)
	)
)
